# T6G (Grand Teton) — schematic netlist excerpt (pin names and nets, part order shuffled) for the footprints in the layout excerpt that follows; sources: Cadence DE-HDL packaged netlist, KiCad conversion of 04192023_DAF0TMB3IC0_F0TG_MB_C_brd_V02_OCP.brd

PU40  ISL99390FRZTR5935  ISL99390FRZ-TR5935 IC  pkg QFN21_6X5XB  page 222
  VOS  = PVDDIO_P1_VOS2
  AGND  = GND
  VCC  = PVDDIO_P1_VCC2
  PVCC  = PVDDCR_CPU1_P1_PVCC
  PGND1  = GND
  GL1  = NC_PVDDIO_P1_GL1_2
  PGND2  = GND
  SW  = SW_PVDDIO_P1_SW2
  VIN1  = SW_P12V_AUX_PVDDIO_P1_FLT
  VIN2  = SW_P12V_AUX_PVDDIO_P1_FLT
  DNC  = NC_PVDDIO_P1_DNC2
  PHASE  = SW_PVDDIO_P1_BOOTR2
  BOOT  = SW_PVDDIO_P1_BOOT2
  PWM  = PVDDIO_P1_PWM2
  EN  = PVDDIO_P1_VCC2
  TOUT_FLT  = PVDDIO_P1_TEMP1
  LSET  = PVDDIO_P1_LSET2
  IOUT  = PVDDIO_P1_IMON2
  REFIN  = PVDDCR_CPU1_P1_VCCS
  PGND3  = GND
  GL2  = NC_PVDDIO_P1_GL2_2

(kicad_pcb
	(version 20260206)
	(generator "pcbnew")
	(generator_version "10.0")
	(general
		(thickness 1.6)
		(legacy_teardrops no)
	)
	(paper "A4")
	(title_block
		(title "04192023_DAF0TMB3IC0_F0TG_MB_C_brd_V02_OCP.brd")
		(comment 1 "Grand Teton / footprints 752-752 of 8354")
	)
	(layers
		(0 "F.Cu" signal "TOP")
		(4 "In1.Cu" signal "GND")
		(6 "In2.Cu" signal "IN1")
		(8 "In3.Cu" signal "GND1")
		(10 "In4.Cu" signal "IN2")
		(12 "In5.Cu" signal "GND2")
		(14 "In6.Cu" signal "IN3")
		(16 "In7.Cu" signal "GND3")
		(18 "In8.Cu" signal "VCC")
		(20 "In9.Cu" signal "VCC1")
		(22 "In10.Cu" signal "GND4")
		(24 "In11.Cu" signal "IN4")
		(26 "In12.Cu" signal "GND5")
		(28 "In13.Cu" signal "IN5")
		(30 "In14.Cu" signal "GND6")
		(32 "In15.Cu" signal "IN6")
		(34 "In16.Cu" signal "GND7")
		(2 "B.Cu" signal "BOTTOM")
		(9 "F.Adhes" user "F.Adhesive")
		(11 "B.Adhes" user "B.Adhesive")
		(13 "F.Paste" user "Package Geometry/Pastemask Top")
		(15 "B.Paste" user "Package Geometry/Pastemask Bottom")
		(5 "F.SilkS" user "Ref Des/Silkscreen Top")
		(7 "B.SilkS" user "Ref Des/Silkscreen Bottom")
		(1 "F.Mask" user "Board Geometry/Soldermask Top")
		(3 "B.Mask" user "Board Geometry/Soldermask Bottom")
		(17 "Dwgs.User" user "User.Drawings")
		(19 "Cmts.User" user "User.Comments")
		(21 "Eco1.User" user "User.Eco1")
		(23 "Eco2.User" user "User.Eco2")
		(25 "Edge.Cuts" user "Board Geometry/Outline")
		(27 "Margin" user)
		(31 "F.CrtYd" user "Package Geometry/Place Bound Top")
		(29 "B.CrtYd" user "Package Geometry/Place Bound Bottom")
		(35 "F.Fab" user "Ref Des/Assembly Top")
		(33 "B.Fab" user "Ref Des/Assembly Bottom")
	)
	(footprint ""
		(layer "F.Cu")
		(at 45.186854 -346.721176)
		(property "Reference" "PU40"
			(at -3.022854 -7.709154 0)
			(unlocked yes)
			(layer "F.SilkS")
			(effects
				(font
					(size 0.7874 0.5842)
					(thickness 0.1524)
				)
				(justify left)
			)
		)
		(property "Value" ""
			(at 0 0 0)
			(layer "F.Fab")
			(effects
				(font
					(size 1.27 1.27)
				)
			)
		)
		(duplicate_pad_numbers_are_jumpers no)
		(fp_line
			(start -2.500122 -2.999994)
			(end -2.24409 -2.999994)
			(stroke
				(width 0.1524)
				(type default)
			)
			(layer "F.SilkS")
		)
		(fp_line
			(start -2.500122 -2.529078)
			(end -2.500122 -2.999994)
			(stroke
				(width 0.1524)
				(type default)
			)
			(layer "F.SilkS")
		)
		(fp_line
			(start -2.500122 0.6604)
			(end -2.500122 0.229108)
			(stroke
				(width 0.1524)
				(type default)
			)
			(layer "F.SilkS")
		)
		(fp_line
			(start -2.500122 2.999994)
			(end -2.500122 2.339594)
			(stroke
				(width 0.1524)
				(type default)
			)
			(layer "F.SilkS")
		)
		(fp_line
			(start -2.2987 2.999994)
			(end -2.500122 2.999994)
			(stroke
				(width 0.1524)
				(type default)
			)
			(layer "F.SilkS")
		)
		(fp_line
			(start 2.31394 -2.999994)
			(end 2.500122 -2.999994)
			(stroke
				(width 0.1524)
				(type default)
			)
			(layer "F.SilkS")
		)
		(fp_line
			(start 2.500122 -2.999994)
			(end 2.500122 -2.44348)
			(stroke
				(width 0.1524)
				(type default)
			)
			(layer "F.SilkS")
		)
		(fp_line
			(start 2.500122 2.339594)
			(end 2.500122 2.999994)
			(stroke
				(width 0.1524)
				(type default)
			)
			(layer "F.SilkS")
		)
		(fp_line
			(start 2.500122 2.999994)
			(end 2.2987 2.999994)
			(stroke
				(width 0.1524)
				(type default)
			)
			(layer "F.SilkS")
		)
		(fp_poly
			(pts
				(xy -2.70129 -2.450084) (xy -3.374898 -2.674366) (xy -2.925826 -3.123438)
			)
			(stroke
				(width 0)
				(type default)
			)
			(fill yes)
			(layer "F.SilkS")
		)
		(fp_line
			(start -2.500122 -2.999994)
			(end 2.500122 -2.999994)
			(stroke
				(width 0.1)
				(type default)
			)
			(layer "F.Fab")
		)
		(fp_line
			(start -2.500122 2.999994)
			(end -2.500122 -2.999994)
			(stroke
				(width 0.1)
				(type default)
			)
			(layer "F.Fab")
		)
		(fp_line
			(start 2.500122 -2.999994)
			(end 2.500122 2.999994)
			(stroke
				(width 0.1)
				(type default)
			)
			(layer "F.Fab")
		)
		(fp_line
			(start 2.500122 2.999994)
			(end -2.500122 2.999994)
			(stroke
				(width 0.1)
				(type default)
			)
			(layer "F.Fab")
		)
		(fp_poly
			(pts
				(xy -4.218432 -2.783078) (xy -4.218432 -1.767078) (xy -3.202432 -2.275078)
			)
			(stroke
				(width 0)
				(type default)
			)
			(fill yes)
			(layer "F.Fab")
		)
		(pad "1" smd rect
			(at -2.400046 -2.275078 90)
			(size 0.2286 0.6096)
			(layers "F.Cu" "F.Mask" "F.Paste")
			(net "PVDDIO_P1_VOS2")
		)
		(pad "2" smd rect
			(at -2.400046 -1.82499 90)
			(size 0.2286 0.6096)
			(layers "F.Cu" "F.Mask" "F.Paste")
			(net "GND")
		)
		(pad "3" smd rect
			(at -2.400046 -1.374902 90)
			(size 0.2286 0.6096)
			(layers "F.Cu" "F.Mask" "F.Paste")
			(net "PVDDIO_P1_VCC2")
		)
		(pad "4" smd rect
			(at -2.400046 -0.925068 90)
			(size 0.2286 0.6096)
			(layers "F.Cu" "F.Mask" "F.Paste")
			(net "PVDDCR_CPU1_P1_PVCC")
		)
		(pad "5" smd rect
			(at -2.400046 -0.47498 90)
			(size 0.2286 0.6096)
			(layers "F.Cu" "F.Mask" "F.Paste")
			(net "GND")
		)
		(pad "6" smd rect
			(at -2.400046 -0.024892 90)
			(size 0.2286 0.6096)
			(layers "F.Cu" "F.Mask" "F.Paste")
			(net "NC_PVDDIO_P1_GL1_2")
		)
		(pad "7_9-20_24" smd circle
			(at 0 1.150112 90)
			(size 0 0)
			(layers "F.Cu" "F.Mask" "F.Paste")
			(net "GND")
		)
		(pad "10_19" smd rect
			(at 0 2.899918 90)
			(size 0.6096 4.318)
			(layers "F.Cu" "F.Mask" "F.Paste")
			(net "SW_PVDDIO_P1_SW2")
		)
		(pad "25_29" smd rect
			(at 1.549908 -1.279906 270)
			(size 2.0574 2.3114)
			(layers "F.Cu" "F.Mask" "F.Paste")
			(net "SW_P12V_AUX_PVDDIO_P1_FLT")
		)
		(pad "30" smd rect
			(at 2.05994 -2.899918)
			(size 0.2286 0.6096)
			(layers "F.Cu" "F.Mask" "F.Paste")
			(net "SW_P12V_AUX_PVDDIO_P1_FLT")
		)
		(pad "31" smd rect
			(at 1.610106 -2.899918)
			(size 0.2286 0.6096)
			(layers "F.Cu" "F.Mask" "F.Paste")
			(net "NC_PVDDIO_P1_DNC2")
		)
		(pad "32" smd rect
			(at 1.160018 -2.899918)
			(size 0.2286 0.6096)
			(layers "F.Cu" "F.Mask" "F.Paste")
			(net "SW_PVDDIO_P1_BOOTR2")
		)
		(pad "33" smd rect
			(at 0.70993 -2.899918)
			(size 0.2286 0.6096)
			(layers "F.Cu" "F.Mask" "F.Paste")
			(net "SW_PVDDIO_P1_BOOT2")
		)
		(pad "34" smd rect
			(at 0.260096 -2.899918)
			(size 0.2286 0.6096)
			(layers "F.Cu" "F.Mask" "F.Paste")
			(net "PVDDIO_P1_PWM2")
		)
		(pad "35" smd rect
			(at -0.189992 -2.899918)
			(size 0.2286 0.6096)
			(layers "F.Cu" "F.Mask" "F.Paste")
			(net "PVDDIO_P1_VCC2")
		)
		(pad "36" smd rect
			(at -0.64008 -2.899918)
			(size 0.2286 0.6096)
			(layers "F.Cu" "F.Mask" "F.Paste")
			(net "PVDDIO_P1_TEMP1")
		)
		(pad "37" smd rect
			(at -1.089914 -2.899918)
			(size 0.2286 0.6096)
			(layers "F.Cu" "F.Mask" "F.Paste")
			(net "PVDDIO_P1_LSET2")
		)
		(pad "38" smd rect
			(at -1.540002 -2.899918)
			(size 0.2286 0.6096)
			(layers "F.Cu" "F.Mask" "F.Paste")
			(net "PVDDIO_P1_IMON2")
		)
		(pad "39" smd rect
			(at -1.99009 -2.899918)
			(size 0.2286 0.6096)
			(layers "F.Cu" "F.Mask" "F.Paste")
			(net "PVDDCR_CPU1_P1_VCCS")
		)
		(pad "40" smd rect
			(at -0.87503 -1.27508)
			(size 1.7526 1.9558)
			(layers "F.Cu" "F.Mask" "F.Paste")
			(net "GND")
		)
		(pad "41" smd rect
			(at -1.525016 0.249936 270)
			(size 0.3048 0.4572)
			(layers "F.Cu" "F.Mask" "F.Paste")
			(net "NC_PVDDIO_P1_GL2_2")
		)
		(zone
			(layer "F.Cu")
			(hatch none 0.5)
			(connect_pads
				(clearance 0)
			)
			(min_thickness 0.25)
			(keepout
				(tracks not_allowed)
				(vias allowed)
				(pads allowed)
				(copperpour not_allowed)
				(footprints allowed)
			)
			(placement
				(enabled no)
				(sheetname "")
			)
			(fill
				(thermal_gap 0.5)
				(thermal_bridge_width 0.5)
				(island_removal_mode 0)
			)
			(polygon
				(pts
					(xy 42.686732 -344.1446) (xy 42.686732 -344.470482) (xy 47.686976 -344.470482) (xy 47.686976 -344.148664)
					(xy 47.396654 -344.148664) (xy 47.396654 -344.176858) (xy 42.977054 -344.176858) (xy 42.977054 -344.1446)
				)
			)
		)
		(zone
			(layer "F.Cu")
			(hatch none 0.5)
			(connect_pads
				(clearance 0)
			)
			(min_thickness 0.25)
			(keepout
				(tracks not_allowed)
				(vias allowed)
				(pads allowed)
				(copperpour not_allowed)
				(footprints allowed)
			)
			(placement
				(enabled no)
				(sheetname "")
			)
			(fill
				(thermal_gap 0.5)
				(thermal_bridge_width 0.5)
				(island_removal_mode 0)
			)
			(polygon
				(pts
					(xy 45.2374 -346.967556) (xy 45.238924 -346.967556) (xy 45.238924 -349.024956) (xy 43.384724 -349.024956)
					(xy 43.384724 -348.78391) (xy 43.142408 -348.78391) (xy 43.142408 -349.265494) (xy 46.98238 -349.265494)
					(xy 46.98238 -349.080582) (xy 45.530262 -349.080582) (xy 45.530262 -346.921582) (xy 47.686976 -346.921582)
					(xy 47.686976 -346.6719) (xy 45.456856 -346.6719) (xy 45.2374 -346.891356)
				)
			)
		)
	)
)
